(kicad_pcb
	(version 20260206)
	(generator "pcbnew")
	(generator_version "10.0")
	(general
		(thickness 1.21888)
		(legacy_teardrops no)
	)
	(paper "A4")
	(title_block
		(title "timecard-v9 — TimeCard-DC-V9_EXP.PcbDoc")
		(comment 1 "Time Appliance Project (Time Card) / footprints 117-124 of 402")
	)
	(layers
		(0 "F.Cu" signal "TOP")
		(4 "In1.Cu" signal "SGND")
		(6 "In2.Cu" signal "IN1")
		(8 "In3.Cu" signal "IN2")
		(10 "In4.Cu" signal "SGND1")
		(2 "B.Cu" signal "BOTTOM")
		(9 "F.Adhes" user "F.Adhesive")
		(11 "B.Adhes" user "B.Adhesive")
		(13 "F.Paste" user "Top Paste")
		(15 "B.Paste" user "Bottom Paste")
		(5 "F.SilkS" user "Top Overlay")
		(7 "B.SilkS" user "Bottom Overlay")
		(1 "F.Mask" user "Top Solder")
		(3 "B.Mask" user "Bottom Solder")
		(17 "Dwgs.User" user "User.Drawings")
		(19 "Cmts.User" user "User.Comments")
		(21 "Eco1.User" user "User.Eco1")
		(23 "Eco2.User" user "User.Eco2")
		(25 "Edge.Cuts" user)
		(27 "Margin" user)
		(31 "F.CrtYd" user "Top Courtyard")
		(29 "B.CrtYd" user "Bottom Courtyard")
		(35 "F.Fab" user "Top Component Center")
		(33 "B.Fab" user "Bottom Component Center")
	)
	(footprint "Vault:RESC1005X40X25LL05T10"
		(layer "F.Cu")
		(at 112.4216 58.0162 -90)
		(property "Reference" "R150"
			(at 2.7032 0.026931 270)
			(unlocked yes)
			(layer "F.SilkS")
			(effects
				(font
					(size 0.762 0.762)
					(thickness 0.2032)
				)
			)
		)
		(property "Value" "49.9_1%_0402"
			(at -2.579871 8.798275 180)
			(unlocked yes)
			(layer "F.SilkS")
			(hide yes)
			(effects
				(font
					(size 0.762 0.762)
					(thickness 0.2032)
				)
			)
		)
		(sheetname "11-M2_RCB_MUX")
		(sheetfile "11-M2_RCB_MUX.kicad_sch")
		(duplicate_pad_numbers_are_jumpers no)
		(pad "1" smd rect
			(at -0.375 0)
			(size 0.45 0.5)
			(layers "F.Cu" "F.Mask" "F.Paste")
			(net "NetR150_1")
		)
		(pad "2" smd rect
			(at 0.375 0)
			(size 0.45 0.5)
			(layers "F.Cu" "F.Mask" "F.Paste")
			(net "GPS1_TP1")
		)
	)
	(footprint "Vault:FP-T521X476M035ATE030-MFG"
		(layer "F.Cu")
		(at 96.8216 52.0162 180)
		(property "Reference" "C72"
			(at 4.673069 -1.6968 90)
			(unlocked yes)
			(layer "F.SilkS")
			(effects
				(font
					(size 0.762 0.762)
					(thickness 0.2032)
				)
			)
		)
		(property "Value" "47uF_35V_2917"
			(at -5.843751 7.45182 90)
			(unlocked yes)
			(layer "F.SilkS")
			(hide yes)
			(effects
				(font
					(size 0.762 0.762)
					(thickness 0.2032)
				)
			)
		)
		(sheetname "03-POWER")
		(sheetfile "03-POWER.kicad_sch")
		(duplicate_pad_numbers_are_jumpers no)
		(fp_line
			(start 5 1.52399)
			(end 4.4 1.52399)
			(stroke
				(width 0.2)
				(type solid)
			)
			(layer "F.SilkS")
		)
		(fp_line
			(start 4.7 1.22399)
			(end 4.7 1.82399)
			(stroke
				(width 0.2)
				(type solid)
			)
			(layer "F.SilkS")
		)
		(fp_line
			(start 3.8 2.3)
			(end -3.8 2.3)
			(stroke
				(width 0.2)
				(type solid)
			)
			(layer "F.SilkS")
		)
		(fp_line
			(start 3.8 1.54)
			(end 3.8 2.3)
			(stroke
				(width 0.2)
				(type solid)
			)
			(layer "F.SilkS")
		)
		(fp_line
			(start 3.8 -2.3)
			(end 3.8 -1.54)
			(stroke
				(width 0.2)
				(type solid)
			)
			(layer "F.SilkS")
		)
		(fp_line
			(start 3.8 -2.3)
			(end -3.8 -2.3)
			(stroke
				(width 0.2)
				(type solid)
			)
			(layer "F.SilkS")
		)
		(fp_line
			(start -3.8 1.54)
			(end -3.8 2.3)
			(stroke
				(width 0.2)
				(type solid)
			)
			(layer "F.SilkS")
		)
		(fp_line
			(start -3.8 -2.3)
			(end -3.8 -1.54)
			(stroke
				(width 0.2)
				(type solid)
			)
			(layer "F.SilkS")
		)
		(fp_line
			(start 4.13 2.42)
			(end -4.13 2.42)
			(stroke
				(width 0.2)
				(type solid)
			)
			(layer "F.CrtYd")
		)
		(fp_line
			(start 4.13 -2.42)
			(end 4.13 2.42)
			(stroke
				(width 0.2)
				(type solid)
			)
			(layer "F.CrtYd")
		)
		(fp_line
			(start 4.13 -2.42)
			(end -4.13 -2.42)
			(stroke
				(width 0.2)
				(type solid)
			)
			(layer "F.CrtYd")
		)
		(fp_line
			(start -4.13 -2.42)
			(end -4.13 2.42)
			(stroke
				(width 0.2)
				(type solid)
			)
			(layer "F.CrtYd")
		)
		(fp_line
			(start 4.13 2.42)
			(end -4.13 2.42)
			(stroke
				(width 0.2)
				(type solid)
			)
			(layer "F.Fab")
		)
		(fp_line
			(start 4.13 -2.42)
			(end 4.13 2.42)
			(stroke
				(width 0.2)
				(type solid)
			)
			(layer "F.Fab")
		)
		(fp_line
			(start 4.13 -2.42)
			(end -4.13 -2.42)
			(stroke
				(width 0.2)
				(type solid)
			)
			(layer "F.Fab")
		)
		(fp_line
			(start 0.5 0)
			(end -0.5 0)
			(stroke
				(width 0.1)
				(type solid)
			)
			(layer "F.Fab")
		)
		(fp_line
			(start 0 -0.5)
			(end 0 0.5)
			(stroke
				(width 0.1)
				(type solid)
			)
			(layer "F.Fab")
		)
		(fp_line
			(start -4.13 -2.42)
			(end -4.13 2.42)
			(stroke
				(width 0.2)
				(type solid)
			)
			(layer "F.Fab")
		)
		(fp_text user "${REFERENCE}"
			(at 0 0.28425 180)
			(unlocked yes)
			(layer "F.Fab")
			(effects
				(font
					(face "Arial")
					(size 0.63 0.63)
					(thickness 0.1)
				)
				(justify left bottom)
			)
		)
		(pad "1" smd rect
			(at -3.01 0 180)
			(size 1.99 2.33)
			(layers "F.Cu" "F.Mask" "F.Paste")
			(net "GND")
			(solder_mask_margin 0)
			(solder_paste_margin 0)
		)
		(pad "2" smd rect
			(at 3.01 0 180)
			(size 1.99 2.33)
			(layers "F.Cu" "F.Mask" "F.Paste")
			(net "+12V")
			(solder_mask_margin 0)
			(solder_paste_margin 0)
		)
	)
	(footprint "Vault:FP-C3216-160-0_2-MFG"
		(layer "F.Cu")
		(at 92.72394 70.79377 180)
		(property "Reference" "C13"
			(at 1.10234 1.284225 0)
			(unlocked yes)
			(layer "F.SilkS")
			(effects
				(font
					(size 0.762 0.762)
					(thickness 0.2286)
				)
				(justify left bottom)
			)
		)
		(property "Value" "47uF_16V_1206"
			(at -0.3062 -14.963945 0)
			(unlocked yes)
			(layer "F.SilkS")
			(hide yes)
			(effects
				(font
					(size 0.762 0.762)
					(thickness 0.2286)
				)
				(justify left bottom)
			)
		)
		(sheetname "03-POWER")
		(sheetfile "03-POWER.kicad_sch")
		(duplicate_pad_numbers_are_jumpers no)
		(fp_line
			(start 0.725 0.9)
			(end -0.725 0.9)
			(stroke
				(width 0.2)
				(type solid)
			)
			(layer "F.SilkS")
		)
		(fp_line
			(start 0.725 -0.9)
			(end -0.725 -0.9)
			(stroke
				(width 0.2)
				(type solid)
			)
			(layer "F.SilkS")
		)
		(fp_line
			(start 2.3 1)
			(end -2.3 1)
			(stroke
				(width 0.2)
				(type solid)
			)
			(layer "F.CrtYd")
		)
		(fp_line
			(start 2.3 -1)
			(end 2.3 1)
			(stroke
				(width 0.2)
				(type solid)
			)
			(layer "F.CrtYd")
		)
		(fp_line
			(start 2.3 -1)
			(end -2.3 -1)
			(stroke
				(width 0.2)
				(type solid)
			)
			(layer "F.CrtYd")
		)
		(fp_line
			(start -2.3 -1)
			(end -2.3 1)
			(stroke
				(width 0.2)
				(type solid)
			)
			(layer "F.CrtYd")
		)
		(fp_line
			(start 2.3 1)
			(end -2.3 1)
			(stroke
				(width 0.2)
				(type solid)
			)
			(layer "F.Fab")
		)
		(fp_line
			(start 2.3 -1)
			(end 2.3 1)
			(stroke
				(width 0.2)
				(type solid)
			)
			(layer "F.Fab")
		)
		(fp_line
			(start 2.3 -1)
			(end -2.3 -1)
			(stroke
				(width 0.2)
				(type solid)
			)
			(layer "F.Fab")
		)
		(fp_line
			(start 0.5 0)
			(end -0.5 0)
			(stroke
				(width 0.1)
				(type solid)
			)
			(layer "F.Fab")
		)
		(fp_line
			(start 0 -0.5)
			(end 0 0.5)
			(stroke
				(width 0.1)
				(type solid)
			)
			(layer "F.Fab")
		)
		(fp_line
			(start -2.3 -1)
			(end -2.3 1)
			(stroke
				(width 0.2)
				(type solid)
			)
			(layer "F.Fab")
		)
		(fp_text user "${REFERENCE}"
			(at -0.00001 0.09602 180)
			(unlocked yes)
			(layer "F.Fab")
			(effects
				(font
					(face "Arial")
					(size 0.63 0.63)
					(thickness 0.1)
				)
				(justify left bottom)
			)
		)
		(pad "1" smd rect
			(at -1.65 0 180)
			(size 1.1 1.35)
			(layers "F.Cu" "F.Mask" "F.Paste")
			(net "+5.0V")
			(solder_mask_margin 0)
			(solder_paste_margin 0)
		)
		(pad "2" smd rect
			(at 1.65 0 180)
			(size 1.1 1.35)
			(layers "F.Cu" "F.Mask" "F.Paste")
			(net "GND")
			(solder_mask_margin 0)
			(solder_paste_margin 0)
		)
	)
	(footprint "Vault:CAPC1608X87X45ML20T05"
		(layer "F.Cu")
		(at 88.35686 86.56371 90)
		(property "Reference" "C40"
			(at 0.4786 -3.473069 90)
			(unlocked yes)
			(layer "F.SilkS")
			(effects
				(font
					(size 0.762 0.762)
					(thickness 0.2286)
				)
			)
		)
		(property "Value" "0.1uF"
			(at 2.069035 2.630671 90)
			(unlocked yes)
			(layer "F.SilkS")
			(hide yes)
			(effects
				(font
					(size 0.762 0.762)
					(thickness 0.2286)
				)
			)
		)
		(sheetname "02-USER_IO_STATUS")
		(sheetfile "02-USER_IO_STATUS.kicad_sch")
		(duplicate_pad_numbers_are_jumpers no)
		(pad "1" smd rect
			(at -0.7 0 180)
			(size 1.1 1.05)
			(layers "F.Cu" "F.Mask" "F.Paste")
			(net "GND")
		)
		(pad "2" smd rect
			(at 0.7 0 180)
			(size 1.1 1.05)
			(layers "F.Cu" "F.Mask" "F.Paste")
			(net "+3.3V")
		)
	)
	(footprint "Vault:FP-0603-L_1_6_0_2-W_0_8_0-MFG"
		(layer "F.Cu")
		(at 109.8216 80.91748 -90)
		(property "Reference" "C8"
			(at -2.4 0.493345 270)
			(unlocked yes)
			(layer "F.SilkS")
			(effects
				(font
					(size 0.762 0.762)
					(thickness 0.2286)
				)
				(justify left bottom)
			)
		)
		(property "Value" "10uF_16V_0603"
			(at 31.257845 -2.1089 0)
			(unlocked yes)
			(layer "F.SilkS")
			(hide yes)
			(effects
				(font
					(size 0.762 0.762)
					(thickness 0.2286)
				)
				(justify left bottom)
			)
		)
		(sheetname "05-GPS_IMU_SENSORS")
		(sheetfile "05-GPS_IMU_SENSORS.kicad_sch")
		(duplicate_pad_numbers_are_jumpers no)
		(fp_line
			(start 0.9 0.825)
			(end -0.9 0.825)
			(stroke
				(width 0.2)
				(type solid)
			)
			(layer "F.SilkS")
		)
		(fp_line
			(start 0.9 -0.825)
			(end -0.9 -0.825)
			(stroke
				(width 0.2)
				(type solid)
			)
			(layer "F.SilkS")
		)
		(fp_line
			(start -1.15 0.6)
			(end -1.15 -0.6)
			(stroke
				(width 0.2)
				(type solid)
			)
			(layer "F.CrtYd")
		)
		(fp_line
			(start 1.15 0.6)
			(end -1.15 0.6)
			(stroke
				(width 0.2)
				(type solid)
			)
			(layer "F.CrtYd")
		)
		(fp_line
			(start 1.15 0.6)
			(end 1.15 -0.6)
			(stroke
				(width 0.2)
				(type solid)
			)
			(layer "F.CrtYd")
		)
		(fp_line
			(start 1.15 -0.6)
			(end -1.15 -0.6)
			(stroke
				(width 0.2)
				(type solid)
			)
			(layer "F.CrtYd")
		)
		(fp_line
			(start -1.15 0.6)
			(end -1.15 -0.6)
			(stroke
				(width 0.2)
				(type solid)
			)
			(layer "F.Fab")
		)
		(fp_line
			(start 1.15 0.6)
			(end -1.15 0.6)
			(stroke
				(width 0.2)
				(type solid)
			)
			(layer "F.Fab")
		)
		(fp_line
			(start 1.15 0.6)
			(end 1.15 -0.6)
			(stroke
				(width 0.2)
				(type solid)
			)
			(layer "F.Fab")
		)
		(fp_line
			(start 0 0.5)
			(end 0 -0.5)
			(stroke
				(width 0.1)
				(type solid)
			)
			(layer "F.Fab")
		)
		(fp_line
			(start 0.5 0)
			(end -0.5 0)
			(stroke
				(width 0.1)
				(type solid)
			)
			(layer "F.Fab")
		)
		(fp_line
			(start 1.15 -0.6)
			(end -1.15 -0.6)
			(stroke
				(width 0.2)
				(type solid)
			)
			(layer "F.Fab")
		)
		(fp_text user "${REFERENCE}"
			(at -0.00001 0.09602 270)
			(unlocked yes)
			(layer "F.Fab")
			(effects
				(font
					(face "Arial")
					(size 0.63 0.63)
					(thickness 0.1)
				)
				(justify left bottom)
			)
		)
		(pad "1" smd rect
			(at -0.7 0 270)
			(size 0.7 0.7)
			(layers "F.Cu" "F.Mask" "F.Paste")
			(net "BNO_P3V3")
			(solder_mask_margin 0)
			(solder_paste_margin 0)
		)
		(pad "2" smd rect
			(at 0.7 0 270)
			(size 0.7 0.7)
			(layers "F.Cu" "F.Mask" "F.Paste")
			(net "GND")
			(solder_mask_margin 0)
			(solder_paste_margin 0)
		)
	)
	(footprint "Vault:FP-LTST-C191KGKT-MFG"
		(layer "F.Cu")
		(at 223.9216 93.2162)
		(property "Reference" "D19"
			(at -2.8968 0.126921 0)
			(unlocked yes)
			(layer "F.SilkS")
			(effects
				(font
					(size 0.762 0.762)
					(thickness 0.2032)
				)
			)
		)
		(property "Value" "LTST-C191KGKT"
			(at -3.494271 8.97586 270)
			(unlocked yes)
			(layer "F.SilkS")
			(hide yes)
			(effects
				(font
					(size 0.762 0.762)
					(thickness 0.2032)
				)
			)
		)
		(sheetname "08-DIPSwitches_I2C")
		(sheetfile "08-DIPSwitches_I2C.kicad_sch")
		(duplicate_pad_numbers_are_jumpers no)
		(fp_line
			(start -0.85 -0.775)
			(end 0.85 -0.775)
			(stroke
				(width 0.2)
				(type solid)
			)
			(layer "F.SilkS")
		)
		(fp_line
			(start -0.85 0.775)
			(end 0.85 0.775)
			(stroke
				(width 0.2)
				(type solid)
			)
			(layer "F.SilkS")
		)
		(fp_circle
			(center -1.7 0)
			(end -1.7 -0.125)
			(stroke
				(width 0.25)
				(type solid)
			)
			(fill no)
			(layer "F.SilkS")
		)
		(fp_line
			(start -1.25 -0.55)
			(end 1.25 -0.55)
			(stroke
				(width 0.2)
				(type solid)
			)
			(layer "F.CrtYd")
		)
		(fp_line
			(start -1.25 0.55)
			(end -1.25 -0.55)
			(stroke
				(width 0.2)
				(type solid)
			)
			(layer "F.CrtYd")
		)
		(fp_line
			(start -1.25 0.55)
			(end 1.25 0.55)
			(stroke
				(width 0.2)
				(type solid)
			)
			(layer "F.CrtYd")
		)
		(fp_line
			(start 1.25 0.55)
			(end 1.25 -0.55)
			(stroke
				(width 0.2)
				(type solid)
			)
			(layer "F.CrtYd")
		)
		(fp_line
			(start -1.25 -0.55)
			(end 1.25 -0.55)
			(stroke
				(width 0.2)
				(type solid)
			)
			(layer "F.Fab")
		)
		(fp_line
			(start -1.25 0.55)
			(end -1.25 -0.55)
			(stroke
				(width 0.2)
				(type solid)
			)
			(layer "F.Fab")
		)
		(fp_line
			(start -1.25 0.55)
			(end 1.25 0.55)
			(stroke
				(width 0.2)
				(type solid)
			)
			(layer "F.Fab")
		)
		(fp_line
			(start -0.5 0)
			(end 0.5 0)
			(stroke
				(width 0.1)
				(type solid)
			)
			(layer "F.Fab")
		)
		(fp_line
			(start 0 0.5)
			(end 0 -0.5)
			(stroke
				(width 0.1)
				(type solid)
			)
			(layer "F.Fab")
		)
		(fp_line
			(start 1.25 0.55)
			(end 1.25 -0.55)
			(stroke
				(width 0.2)
				(type solid)
			)
			(layer "F.Fab")
		)
		(fp_text user "${REFERENCE}"
			(at 0 0.28425 360)
			(unlocked yes)
			(layer "F.Fab")
			(effects
				(font
					(face "Arial")
					(size 0.63 0.63)
					(thickness 0.1)
				)
				(justify left bottom)
			)
		)
		(pad "1" smd rect
			(at -0.75 0)
			(size 0.8 0.8)
			(layers "F.Cu" "F.Mask" "F.Paste")
			(net "NetD19_1")
			(solder_mask_margin 0)
			(solder_paste_margin 0)
		)
		(pad "2" smd rect
			(at 0.75 0)
			(size 0.8 0.8)
			(layers "F.Cu" "F.Mask" "F.Paste")
			(net "+3.3V")
			(solder_mask_margin 0)
			(solder_paste_margin 0)
		)
	)
	(footprint "SA53:SolderSocket"
		(locked yes)
		(layer "F.Cu")
		(at 113.3256 140.0162 90)
		(property "Reference" "SKT10"
			(at -3.426921 -0.575395 0)
			(unlocked yes)
			(layer "F.SilkS")
			(effects
				(font
					(size 0.762 0.762)
					(thickness 0.2286)
				)
			)
		)
		(property "Value" "0332-0-43-80-18-27-10-0"
			(at -2.910071 16.1362 0)
			(unlocked yes)
			(layer "F.SilkS")
			(hide yes)
			(effects
				(font
					(size 0.762 0.762)
					(thickness 0.2286)
				)
			)
		)
		(sheetname "06-MAC")
		(sheetfile "06-MAC.kicad_sch")
		(duplicate_pad_numbers_are_jumpers no)
		(pad "1" thru_hole circle
			(at 0 0 90)
			(size 2.54 2.54)
			(drill 2.0066)
			(layers "*.Cu" "*.Mask")
			(remove_unused_layers no)
			(net "MAC_PPS_OUT")
			(thermal_bridge_angle 90)
		)
	)
	(footprint "SA53:SolderSocket"
		(locked yes)
		(layer "F.Cu")
		(at 125.4216 140.0162 90)
		(property "Reference" "SKT4"
			(at -3.426921 3.0286 0)
			(unlocked yes)
			(layer "F.SilkS")
			(effects
				(font
					(size 0.762 0.762)
					(thickness 0.2286)
				)
			)
		)
		(property "Value" "0332-0-43-80-18-27-10-0"
			(at -2.910071 16.1362 0)
			(unlocked yes)
			(layer "F.SilkS")
			(hide yes)
			(effects
				(font
					(size 0.762 0.762)
					(thickness 0.2286)
				)
			)
		)
		(sheetname "06-MAC")
		(sheetfile "06-MAC.kicad_sch")
		(duplicate_pad_numbers_are_jumpers no)
		(pad "1" thru_hole circle
			(at 0 0 90)
			(size 2.54 2.54)
			(drill 2.0066)
			(layers "*.Cu" "*.Mask")
			(remove_unused_layers no)
			(net "MAC_BITE")
			(thermal_bridge_angle 90)
		)
	)
)
